(kicad_pcb
	(version 20260206)
	(generator "pcbnew")
	(generator_version "10.0")
	(general
		(thickness 1.6)
		(legacy_teardrops no)
	)
	(paper "A4")
	(title_block
		(title "v1-chassis-manager — T6M_CM_d_v01_1031_1645.brd")
		(comment 1 "Open CloudServer (Microsoft) / footprints 1377-1386 of 2512")
	)
	(layers
		(0 "F.Cu" signal "TOP")
		(4 "In1.Cu" signal "GND1")
		(6 "In2.Cu" signal "IN1")
		(8 "In3.Cu" signal "VCC1")
		(10 "In4.Cu" signal "VCC2")
		(12 "In5.Cu" signal "GND2")
		(14 "In6.Cu" signal "IN2")
		(16 "In7.Cu" signal "IN3")
		(18 "In8.Cu" signal "GND3")
		(2 "B.Cu" signal "BOTTOM")
		(9 "F.Adhes" user "F.Adhesive")
		(11 "B.Adhes" user "B.Adhesive")
		(13 "F.Paste" user "Package Geometry/Pastemask Top")
		(15 "B.Paste" user "Package Geometry/Pastemask Bottom")
		(5 "F.SilkS" user "Ref Des/Silkscreen Top")
		(7 "B.SilkS" user "Ref Des/Silkscreen Bottom")
		(1 "F.Mask" user "Board Geometry/Soldermask Top")
		(3 "B.Mask" user "Board Geometry/Soldermask Bottom")
		(17 "Dwgs.User" user "User.Drawings")
		(19 "Cmts.User" user "User.Comments")
		(21 "Eco1.User" user "User.Eco1")
		(23 "Eco2.User" user "User.Eco2")
		(25 "Edge.Cuts" user "Board Geometry/Outline")
		(27 "Margin" user)
		(31 "F.CrtYd" user "Package Geometry/Place Bound Top")
		(29 "B.CrtYd" user "Package Geometry/Place Bound Bottom")
		(35 "F.Fab" user "Ref Des/Assembly Top")
		(33 "B.Fab" user "Ref Des/Assembly Bottom")
	)
	(footprint ""
		(layer "F.Cu")
		(at 188.849 -127.254)
		(property "Reference" "R1268"
			(at 6.477 18.82267 0)
			(unlocked yes)
			(layer "F.SilkS")
			(effects
				(font
					(size 0.7874 0.5842)
					(thickness 0.1524)
				)
				(justify left)
			)
		)
		(property "Value" ""
			(at 0 0 0)
			(layer "F.Fab")
			(effects
				(font
					(size 1.27 1.27)
				)
			)
		)
		(duplicate_pad_numbers_are_jumpers no)
		(fp_line
			(start -0.7874 -0.4064)
			(end 0.7874 -0.4064)
			(stroke
				(width 0.1524)
				(type default)
			)
			(layer "F.SilkS")
		)
		(fp_line
			(start -0.7874 0.4064)
			(end -0.7874 -0.4064)
			(stroke
				(width 0.1524)
				(type default)
			)
			(layer "F.SilkS")
		)
		(fp_line
			(start 0.7874 -0.4064)
			(end 0.7874 0.4064)
			(stroke
				(width 0.1524)
				(type default)
			)
			(layer "F.SilkS")
		)
		(fp_line
			(start 0.7874 0.4064)
			(end -0.7874 0.4064)
			(stroke
				(width 0.1524)
				(type default)
			)
			(layer "F.SilkS")
		)
		(fp_poly
			(pts
				(xy -0.508 0.2794) (xy -0.508 0.2286) (xy -0.635 0.2286) (xy -0.635 -0.254) (xy -0.5334 -0.254)
				(xy -0.5334 -0.2794) (xy 0.5334 -0.2794) (xy 0.5334 -0.254) (xy 0.635 -0.254) (xy 0.635 0.254) (xy 0.5334 0.254)
				(xy 0.5334 0.2794)
			)
			(stroke
				(width 0)
				(type default)
			)
			(fill no)
			(layer "F.CrtYd")
		)
		(pad "1" smd rect
			(at 0.40005 0)
			(size 0.4572 0.508)
			(layers "F.Cu" "F.Mask" "F.Paste")
			(net "SIO_JTAG_CPLD1_TMS_R")
		)
		(pad "2" smd rect
			(at -0.40005 0)
			(size 0.4572 0.508)
			(layers "F.Cu" "F.Mask" "F.Paste")
			(net "SIO_JTAG_CPLD1_TMS")
		)
	)
	(footprint ""
		(layer "F.Cu")
		(at 113.361216 -18.649442 90)
		(property "Reference" "C860"
			(at -1.7018 5.742432 90)
			(unlocked yes)
			(layer "F.SilkS")
			(effects
				(font
					(size 0.7874 0.5842)
					(thickness 0.1524)
				)
				(justify left)
			)
		)
		(property "Value" ""
			(at 0 0 90)
			(layer "F.Fab")
			(effects
				(font
					(size 1.27 1.27)
				)
			)
		)
		(duplicate_pad_numbers_are_jumpers no)
		(fp_line
			(start 0.7874 -0.4064)
			(end 0.7874 0.4064)
			(stroke
				(width 0.1524)
				(type default)
			)
			(layer "F.SilkS")
		)
		(fp_line
			(start -0.7874 -0.4064)
			(end 0.7874 -0.4064)
			(stroke
				(width 0.1524)
				(type default)
			)
			(layer "F.SilkS")
		)
		(fp_line
			(start 0 0.381)
			(end 0 -0.381)
			(stroke
				(width 0.1524)
				(type default)
			)
			(layer "F.SilkS")
		)
		(fp_line
			(start 0.7874 0.4064)
			(end -0.7874 0.4064)
			(stroke
				(width 0.1524)
				(type default)
			)
			(layer "F.SilkS")
		)
		(fp_line
			(start -0.7874 0.4064)
			(end -0.7874 -0.4064)
			(stroke
				(width 0.1524)
				(type default)
			)
			(layer "F.SilkS")
		)
		(fp_poly
			(pts
				(xy -0.5334 0.254) (xy -0.635 0.254) (xy -0.635 0.2286) (xy -0.635 -0.254) (xy -0.5334 -0.254) (xy -0.5334 -0.2794)
				(xy 0.5334 -0.2794) (xy 0.5334 -0.254) (xy 0.635 -0.254) (xy 0.635 0.254) (xy 0.5334 0.254) (xy 0.5334 0.2794)
				(xy -0.508 0.2794) (xy -0.5334 0.2794)
			)
			(stroke
				(width 0)
				(type default)
			)
			(fill no)
			(layer "F.CrtYd")
		)
		(pad "1" smd rect
			(at 0.40005 0 90)
			(size 0.4572 0.508)
			(layers "F.Cu" "F.Mask" "F.Paste")
			(net "PV_VTT_DDR_NODE1_REFOUT")
		)
		(pad "2" smd rect
			(at -0.40005 0 90)
			(size 0.4572 0.508)
			(layers "F.Cu" "F.Mask" "F.Paste")
			(net "GND")
		)
	)
	(footprint ""
		(layer "F.Cu")
		(at 33.344104 -117.535452)
		(property "Reference" "C850"
			(at -6.139688 1.072642 0)
			(unlocked yes)
			(layer "F.SilkS")
			(effects
				(font
					(size 0.7874 0.5842)
					(thickness 0.1524)
				)
				(justify left)
			)
		)
		(property "Value" ""
			(at 0 0 0)
			(layer "F.Fab")
			(effects
				(font
					(size 1.27 1.27)
				)
			)
		)
		(duplicate_pad_numbers_are_jumpers no)
		(fp_line
			(start -0.7874 -0.4064)
			(end 0.7874 -0.4064)
			(stroke
				(width 0.1524)
				(type default)
			)
			(layer "F.SilkS")
		)
		(fp_line
			(start -0.7874 0.4064)
			(end -0.7874 -0.4064)
			(stroke
				(width 0.1524)
				(type default)
			)
			(layer "F.SilkS")
		)
		(fp_line
			(start 0 0.381)
			(end 0 -0.381)
			(stroke
				(width 0.1524)
				(type default)
			)
			(layer "F.SilkS")
		)
		(fp_line
			(start 0.7874 -0.4064)
			(end 0.7874 0.4064)
			(stroke
				(width 0.1524)
				(type default)
			)
			(layer "F.SilkS")
		)
		(fp_line
			(start 0.7874 0.4064)
			(end -0.7874 0.4064)
			(stroke
				(width 0.1524)
				(type default)
			)
			(layer "F.SilkS")
		)
		(fp_poly
			(pts
				(xy -0.5334 0.254) (xy -0.635 0.254) (xy -0.635 0.2286) (xy -0.635 -0.254) (xy -0.5334 -0.254) (xy -0.5334 -0.2794)
				(xy 0.5334 -0.2794) (xy 0.5334 -0.254) (xy 0.635 -0.254) (xy 0.635 0.254) (xy 0.5334 0.254) (xy 0.5334 0.2794)
				(xy -0.508 0.2794) (xy -0.5334 0.2794)
			)
			(stroke
				(width 0)
				(type default)
			)
			(fill no)
			(layer "F.CrtYd")
		)
		(pad "1" smd rect
			(at 0.40005 0)
			(size 0.4572 0.508)
			(layers "F.Cu" "F.Mask" "F.Paste")
			(net "FM_CPLD_NODE1_P1V5_EN")
		)
		(pad "2" smd rect
			(at -0.40005 0)
			(size 0.4572 0.508)
			(layers "F.Cu" "F.Mask" "F.Paste")
			(net "GND")
		)
	)
	(footprint ""
		(layer "F.Cu")
		(at 47.10176 -185.205624 90)
		(property "Reference" "R846"
			(at 4.006088 0.055372 90)
			(unlocked yes)
			(layer "F.SilkS")
			(effects
				(font
					(size 0.7874 0.5842)
					(thickness 0.1524)
				)
				(justify left)
			)
		)
		(property "Value" ""
			(at 0 0 90)
			(layer "F.Fab")
			(effects
				(font
					(size 1.27 1.27)
				)
			)
		)
		(duplicate_pad_numbers_are_jumpers no)
		(fp_line
			(start 0.7874 -0.4064)
			(end 0.7874 0.4064)
			(stroke
				(width 0.1524)
				(type default)
			)
			(layer "F.SilkS")
		)
		(fp_line
			(start -0.7874 -0.4064)
			(end 0.7874 -0.4064)
			(stroke
				(width 0.1524)
				(type default)
			)
			(layer "F.SilkS")
		)
		(fp_line
			(start 0.7874 0.4064)
			(end -0.7874 0.4064)
			(stroke
				(width 0.1524)
				(type default)
			)
			(layer "F.SilkS")
		)
		(fp_line
			(start -0.7874 0.4064)
			(end -0.7874 -0.4064)
			(stroke
				(width 0.1524)
				(type default)
			)
			(layer "F.SilkS")
		)
		(fp_poly
			(pts
				(xy -0.508 0.2794) (xy -0.508 0.2286) (xy -0.635 0.2286) (xy -0.635 -0.254) (xy -0.5334 -0.254)
				(xy -0.5334 -0.2794) (xy 0.5334 -0.2794) (xy 0.5334 -0.254) (xy 0.635 -0.254) (xy 0.635 0.254) (xy 0.5334 0.254)
				(xy 0.5334 0.2794)
			)
			(stroke
				(width 0)
				(type default)
			)
			(fill no)
			(layer "F.CrtYd")
		)
		(pad "1" smd rect
			(at 0.40005 0 90)
			(size 0.4572 0.508)
			(layers "F.Cu" "F.Mask" "F.Paste")
			(net "PSU6_AC_OK_R")
		)
		(pad "2" smd rect
			(at -0.40005 0 90)
			(size 0.4572 0.508)
			(layers "F.Cu" "F.Mask" "F.Paste")
			(net "PSU6_AC_OK")
		)
	)
	(footprint ""
		(layer "F.Cu")
		(at 30.55747 -131.833874 180)
		(property "Reference" "R1095"
			(at 1.270254 3.13055 0)
			(unlocked yes)
			(layer "F.SilkS")
			(effects
				(font
					(size 0.7874 0.5842)
					(thickness 0.1524)
				)
				(justify left)
			)
		)
		(property "Value" ""
			(at 0 0 180)
			(layer "F.Fab")
			(effects
				(font
					(size 1.27 1.27)
				)
			)
		)
		(duplicate_pad_numbers_are_jumpers no)
		(fp_line
			(start 0.7874 0.4064)
			(end -0.7874 0.4064)
			(stroke
				(width 0.1524)
				(type default)
			)
			(layer "F.SilkS")
		)
		(fp_line
			(start 0.7874 -0.4064)
			(end 0.7874 0.4064)
			(stroke
				(width 0.1524)
				(type default)
			)
			(layer "F.SilkS")
		)
		(fp_line
			(start -0.7874 0.4064)
			(end -0.7874 -0.4064)
			(stroke
				(width 0.1524)
				(type default)
			)
			(layer "F.SilkS")
		)
		(fp_line
			(start -0.7874 -0.4064)
			(end 0.7874 -0.4064)
			(stroke
				(width 0.1524)
				(type default)
			)
			(layer "F.SilkS")
		)
		(fp_poly
			(pts
				(xy -0.508 0.2794) (xy -0.508 0.2286) (xy -0.635 0.2286) (xy -0.635 -0.254) (xy -0.5334 -0.254)
				(xy -0.5334 -0.2794) (xy 0.5334 -0.2794) (xy 0.5334 -0.254) (xy 0.635 -0.254) (xy 0.635 0.254) (xy 0.5334 0.254)
				(xy 0.5334 0.2794)
			)
			(stroke
				(width 0)
				(type default)
			)
			(fill no)
			(layer "F.CrtYd")
		)
		(pad "1" smd rect
			(at 0.40005 0 180)
			(size 0.4572 0.508)
			(layers "F.Cu" "F.Mask" "F.Paste")
			(net "P1V538_BMC_NODE1_ADJ")
		)
		(pad "2" smd rect
			(at -0.40005 0 180)
			(size 0.4572 0.508)
			(layers "F.Cu" "F.Mask" "F.Paste")
			(net "P1V538_STB_NODE1_ADJ_S")
		)
	)
	(footprint ""
		(layer "F.Cu")
		(at 23.230332 -128.936242 -90)
		(property "Reference" "R1239"
			(at 2.981706 -4.05257 90)
			(unlocked yes)
			(layer "F.SilkS")
			(effects
				(font
					(size 0.7874 0.5842)
					(thickness 0.1524)
				)
				(justify left)
			)
		)
		(property "Value" ""
			(at 0 0 270)
			(layer "F.Fab")
			(effects
				(font
					(size 1.27 1.27)
				)
			)
		)
		(duplicate_pad_numbers_are_jumpers no)
		(fp_line
			(start -0.7874 0.4064)
			(end -0.7874 -0.4064)
			(stroke
				(width 0.1524)
				(type default)
			)
			(layer "F.SilkS")
		)
		(fp_line
			(start 0.7874 0.4064)
			(end -0.7874 0.4064)
			(stroke
				(width 0.1524)
				(type default)
			)
			(layer "F.SilkS")
		)
		(fp_line
			(start -0.7874 -0.4064)
			(end 0.7874 -0.4064)
			(stroke
				(width 0.1524)
				(type default)
			)
			(layer "F.SilkS")
		)
		(fp_line
			(start 0.7874 -0.4064)
			(end 0.7874 0.4064)
			(stroke
				(width 0.1524)
				(type default)
			)
			(layer "F.SilkS")
		)
		(fp_poly
			(pts
				(xy -0.508 0.2794) (xy -0.508 0.2286) (xy -0.635 0.2286) (xy -0.635 -0.254) (xy -0.5334 -0.254)
				(xy -0.5334 -0.2794) (xy 0.5334 -0.2794) (xy 0.5334 -0.254) (xy 0.635 -0.254) (xy 0.635 0.254) (xy 0.5334 0.254)
				(xy 0.5334 0.2794)
			)
			(stroke
				(width 0)
				(type default)
			)
			(fill no)
			(layer "F.CrtYd")
		)
		(pad "1" smd rect
			(at 0.40005 0 270)
			(size 0.4572 0.508)
			(layers "F.Cu" "F.Mask" "F.Paste")
			(net "FM_CPLD_NODE1_P1V05_EN")
		)
		(pad "2" smd rect
			(at -0.40005 0 270)
			(size 0.4572 0.508)
			(layers "F.Cu" "F.Mask" "F.Paste")
			(net "GND")
		)
	)
	(footprint ""
		(layer "F.Cu")
		(at 78.350364 -17.679416 90)
		(property "Reference" "C166"
			(at -4.546854 5.52323 90)
			(unlocked yes)
			(layer "F.SilkS")
			(effects
				(font
					(size 0.7874 0.5842)
					(thickness 0.1524)
				)
				(justify left)
			)
		)
		(property "Value" ""
			(at 0 0 90)
			(layer "F.Fab")
			(effects
				(font
					(size 1.27 1.27)
				)
			)
		)
		(duplicate_pad_numbers_are_jumpers no)
		(fp_line
			(start 0.7874 -0.4064)
			(end 0.7874 0.4064)
			(stroke
				(width 0.1524)
				(type default)
			)
			(layer "F.SilkS")
		)
		(fp_line
			(start -0.7874 -0.4064)
			(end 0.7874 -0.4064)
			(stroke
				(width 0.1524)
				(type default)
			)
			(layer "F.SilkS")
		)
		(fp_line
			(start 0 0.381)
			(end 0 -0.381)
			(stroke
				(width 0.1524)
				(type default)
			)
			(layer "F.SilkS")
		)
		(fp_line
			(start 0.7874 0.4064)
			(end -0.7874 0.4064)
			(stroke
				(width 0.1524)
				(type default)
			)
			(layer "F.SilkS")
		)
		(fp_line
			(start -0.7874 0.4064)
			(end -0.7874 -0.4064)
			(stroke
				(width 0.1524)
				(type default)
			)
			(layer "F.SilkS")
		)
		(fp_poly
			(pts
				(xy -0.5334 0.254) (xy -0.635 0.254) (xy -0.635 0.2286) (xy -0.635 -0.254) (xy -0.5334 -0.254) (xy -0.5334 -0.2794)
				(xy 0.5334 -0.2794) (xy 0.5334 -0.254) (xy 0.635 -0.254) (xy 0.635 0.254) (xy 0.5334 0.254) (xy 0.5334 0.2794)
				(xy -0.508 0.2794) (xy -0.5334 0.2794)
			)
			(stroke
				(width 0)
				(type default)
			)
			(fill no)
			(layer "F.CrtYd")
		)
		(pad "1" smd rect
			(at 0.40005 0 90)
			(size 0.4572 0.508)
			(layers "F.Cu" "F.Mask" "F.Paste")
			(net "PV_VDDR_NODE1")
		)
		(pad "2" smd rect
			(at -0.40005 0 90)
			(size 0.4572 0.508)
			(layers "F.Cu" "F.Mask" "F.Paste")
			(net "GND")
		)
	)
	(footprint ""
		(layer "F.Cu")
		(at 145.780252 -26.193242)
		(property "Reference" "L37"
			(at -1.04394 -1.092454 0)
			(unlocked yes)
			(layer "F.SilkS")
			(effects
				(font
					(size 0.7874 0.5842)
					(thickness 0.1524)
				)
				(justify left)
			)
		)
		(property "Value" ""
			(at 0 0 0)
			(layer "F.Fab")
			(effects
				(font
					(size 1.27 1.27)
				)
			)
		)
		(duplicate_pad_numbers_are_jumpers no)
		(fp_line
			(start -0.7874 -0.4064)
			(end 0.7874 -0.4064)
			(stroke
				(width 0.1524)
				(type default)
			)
			(layer "F.SilkS")
		)
		(fp_line
			(start -0.7874 0.4064)
			(end -0.7874 -0.4064)
			(stroke
				(width 0.1524)
				(type default)
			)
			(layer "F.SilkS")
		)
		(fp_line
			(start -0.0889 0.4064)
			(end -0.0889 -0.4064)
			(stroke
				(width 0.1524)
				(type default)
			)
			(layer "F.SilkS")
		)
		(fp_line
			(start 0.0889 0.4064)
			(end 0.0889 -0.4064)
			(stroke
				(width 0.1524)
				(type default)
			)
			(layer "F.SilkS")
		)
		(fp_line
			(start 0.7874 -0.4064)
			(end 0.7874 0.4064)
			(stroke
				(width 0.1524)
				(type default)
			)
			(layer "F.SilkS")
		)
		(fp_line
			(start 0.7874 0.4064)
			(end -0.7874 0.4064)
			(stroke
				(width 0.1524)
				(type default)
			)
			(layer "F.SilkS")
		)
		(fp_poly
			(pts
				(xy -0.5334 0.254) (xy -0.635 0.254) (xy -0.635 0.2286) (xy -0.635 -0.254) (xy -0.5334 -0.254) (xy -0.5334 -0.2794)
				(xy 0.5334 -0.2794) (xy 0.5334 -0.254) (xy 0.635 -0.254) (xy 0.635 0.254) (xy 0.5334 0.254) (xy 0.5334 0.2794)
				(xy -0.508 0.2794) (xy -0.5334 0.2794)
			)
			(stroke
				(width 0)
				(type default)
			)
			(fill no)
			(layer "F.CrtYd")
		)
		(pad "1" smd rect
			(at 0.40005 0)
			(size 0.4572 0.508)
			(layers "F.Cu" "F.Mask" "F.Paste")
			(net "GND")
		)
		(pad "2" smd rect
			(at -0.40005 0)
			(size 0.4572 0.508)
			(layers "F.Cu" "F.Mask" "F.Paste")
			(net "GNDA")
		)
	)
	(footprint ""
		(layer "F.Cu")
		(at 155.477972 -26.601928)
		(property "Reference" "C534"
			(at 4.576826 0.855218 90)
			(unlocked yes)
			(layer "F.SilkS")
			(effects
				(font
					(size 0.7874 0.5842)
					(thickness 0.1524)
				)
				(justify left)
			)
		)
		(property "Value" ""
			(at 0 0 0)
			(layer "F.Fab")
			(effects
				(font
					(size 1.27 1.27)
				)
			)
		)
		(duplicate_pad_numbers_are_jumpers no)
		(fp_line
			(start -0.7874 -0.4064)
			(end 0.7874 -0.4064)
			(stroke
				(width 0.1524)
				(type default)
			)
			(layer "F.SilkS")
		)
		(fp_line
			(start -0.7874 0.4064)
			(end -0.7874 -0.4064)
			(stroke
				(width 0.1524)
				(type default)
			)
			(layer "F.SilkS")
		)
		(fp_line
			(start 0 0.381)
			(end 0 -0.381)
			(stroke
				(width 0.1524)
				(type default)
			)
			(layer "F.SilkS")
		)
		(fp_line
			(start 0.7874 -0.4064)
			(end 0.7874 0.4064)
			(stroke
				(width 0.1524)
				(type default)
			)
			(layer "F.SilkS")
		)
		(fp_line
			(start 0.7874 0.4064)
			(end -0.7874 0.4064)
			(stroke
				(width 0.1524)
				(type default)
			)
			(layer "F.SilkS")
		)
		(fp_poly
			(pts
				(xy -0.5334 0.254) (xy -0.635 0.254) (xy -0.635 0.2286) (xy -0.635 -0.254) (xy -0.5334 -0.254) (xy -0.5334 -0.2794)
				(xy 0.5334 -0.2794) (xy 0.5334 -0.254) (xy 0.635 -0.254) (xy 0.635 0.254) (xy 0.5334 0.254) (xy 0.5334 0.2794)
				(xy -0.508 0.2794) (xy -0.5334 0.2794)
			)
			(stroke
				(width 0)
				(type default)
			)
			(fill no)
			(layer "F.CrtYd")
		)
		(pad "1" smd rect
			(at 0.40005 0)
			(size 0.4572 0.508)
			(layers "F.Cu" "F.Mask" "F.Paste")
			(net "N21624861")
		)
		(pad "2" smd rect
			(at -0.40005 0)
			(size 0.4572 0.508)
			(layers "F.Cu" "F.Mask" "F.Paste")
			(net "N21624866")
		)
	)
	(footprint ""
		(layer "F.Cu")
		(at 64.899286 -121.044462 -90)
		(property "Reference" "R331"
			(at 6.142736 -8.217916 90)
			(unlocked yes)
			(layer "F.SilkS")
			(effects
				(font
					(size 0.7874 0.5842)
					(thickness 0.1524)
				)
				(justify left)
			)
		)
		(property "Value" ""
			(at 0 0 270)
			(layer "F.Fab")
			(effects
				(font
					(size 1.27 1.27)
				)
			)
		)
		(duplicate_pad_numbers_are_jumpers no)
		(fp_line
			(start -0.7874 0.4064)
			(end -0.7874 -0.4064)
			(stroke
				(width 0.1524)
				(type default)
			)
			(layer "F.SilkS")
		)
		(fp_line
			(start 0.7874 0.4064)
			(end -0.7874 0.4064)
			(stroke
				(width 0.1524)
				(type default)
			)
			(layer "F.SilkS")
		)
		(fp_line
			(start -0.7874 -0.4064)
			(end 0.7874 -0.4064)
			(stroke
				(width 0.1524)
				(type default)
			)
			(layer "F.SilkS")
		)
		(fp_line
			(start 0.7874 -0.4064)
			(end 0.7874 0.4064)
			(stroke
				(width 0.1524)
				(type default)
			)
			(layer "F.SilkS")
		)
		(fp_poly
			(pts
				(xy -0.508 0.2794) (xy -0.508 0.2286) (xy -0.635 0.2286) (xy -0.635 -0.254) (xy -0.5334 -0.254)
				(xy -0.5334 -0.2794) (xy 0.5334 -0.2794) (xy 0.5334 -0.254) (xy 0.635 -0.254) (xy 0.635 0.254) (xy 0.5334 0.254)
				(xy 0.5334 0.2794)
			)
			(stroke
				(width 0)
				(type default)
			)
			(fill no)
			(layer "F.CrtYd")
		)
		(pad "1" smd rect
			(at 0.40005 0 270)
			(size 0.4572 0.508)
			(layers "F.Cu" "F.Mask" "F.Paste")
			(net "P3V3_NODE1")
		)
		(pad "2" smd rect
			(at -0.40005 0 270)
			(size 0.4572 0.508)
			(layers "F.Cu" "F.Mask" "F.Paste")
			(net "BMC_ROMA15")
		)
	)
)
